(kicad_pcb
	(version 20260206)
	(generator "pcbnew")
	(generator_version "10.0")
	(general
		(thickness 1.6)
		(legacy_teardrops no)
	)
	(paper "A4")
	(title_block
		(title "timecard-production-celestica-r4006 — R4006-B0001-02_R01.brd")
		(comment 1 "Time Appliance Project (Time Card) / footprints 169-173 of 1113")
	)
	(layers
		(0 "F.Cu" signal "TOP")
		(4 "In1.Cu" signal "L02_GND1")
		(6 "In2.Cu" signal "L03_SIG1")
		(8 "In3.Cu" signal "L04_GND2")
		(10 "In4.Cu" signal "L05_VCC1")
		(12 "In5.Cu" signal "L06_VCC2")
		(14 "In6.Cu" signal "L07_GND3")
		(16 "In7.Cu" signal "L08_SIG2")
		(18 "In8.Cu" signal "L09_GND4")
		(2 "B.Cu" signal "BOTTOM")
		(9 "F.Adhes" user "F.Adhesive")
		(11 "B.Adhes" user "B.Adhesive")
		(13 "F.Paste" user "Package Geometry/Pastemask Top")
		(15 "B.Paste" user "Package Geometry/Pastemask Bottom")
		(5 "F.SilkS" user "Ref Des/Silkscreen Top")
		(7 "B.SilkS" user "Ref Des/Silkscreen Bottom")
		(1 "F.Mask" user "Board Geometry/Soldermask Top")
		(3 "B.Mask" user "Board Geometry/Soldermask Bottom")
		(17 "Dwgs.User" user "User.Drawings")
		(19 "Cmts.User" user "User.Comments")
		(21 "Eco1.User" user "User.Eco1")
		(23 "Eco2.User" user "User.Eco2")
		(25 "Edge.Cuts" user "Board Geometry/Outline")
		(27 "Margin" user)
		(31 "F.CrtYd" user "Package Geometry/Place Bound Top")
		(29 "B.CrtYd" user "Package Geometry/Place Bound Bottom")
		(35 "F.Fab" user "Ref Des/Assembly Top")
		(33 "B.Fab" user "Ref Des/Assembly Bottom")
	)
	(footprint ""
		(layer "F.Cu")
		(at 23.507192 -66.8528 180)
		(property "Reference" "L18"
			(at -3.035808 0.03683 0)
			(unlocked yes)
			(layer "F.SilkS")
			(effects
				(font
					(size 0.7874 0.5842)
					(thickness 0.1524)
				)
			)
		)
		(property "Value" "VAL*"
			(at 0.014732 2.526538 180)
			(unlocked yes)
			(layer "F.Fab")
			(hide yes)
			(effects
				(font
					(size 0.7874 0.5842)
					(thickness 0.000001)
				)
			)
		)
		(property "Tolerance" "TOL*"
			(at 0.014732 3.503676 180)
			(unlocked yes)
			(layer "Cmts.User")
			(hide yes)
			(effects
				(font
					(size 0.7874 0.5842)
					(thickness 0.000001)
				)
			)
		)
		(property "User Part Number" "PARTNUM*"
			(at 0.02794 4.480814 180)
			(unlocked yes)
			(layer "Cmts.User")
			(hide yes)
			(effects
				(font
					(size 0.7874 0.5842)
					(thickness 0.000001)
				)
			)
		)
		(property "Device Type" "FERRITEBEAD-G191-10097-01,600OA"
			(at 0.014732 1.600708 180)
			(unlocked yes)
			(layer "F.Fab")
			(hide yes)
			(effects
				(font
					(size 0.7874 0.5842)
					(thickness 0.000001)
				)
			)
		)
		(duplicate_pad_numbers_are_jumpers no)
		(fp_line
			(start 1.3208 0.7112)
			(end -1.3208 0.7112)
			(stroke
				(width 0.1)
				(type default)
			)
			(layer "F.SilkS")
		)
		(fp_line
			(start 1.3208 -0.7112)
			(end 1.3208 0.7112)
			(stroke
				(width 0.1)
				(type default)
			)
			(layer "F.SilkS")
		)
		(fp_line
			(start -1.3208 0.7112)
			(end -1.3208 -0.7112)
			(stroke
				(width 0.1)
				(type default)
			)
			(layer "F.SilkS")
		)
		(fp_line
			(start -1.3208 -0.7112)
			(end 1.3208 -0.7112)
			(stroke
				(width 0.1)
				(type default)
			)
			(layer "F.SilkS")
		)
		(fp_rect
			(start -1.3208 0.7112)
			(end 1.3208 -0.7112)
			(stroke
				(width 0)
				(type default)
			)
			(fill no)
			(layer "F.CrtYd")
		)
		(fp_line
			(start 0.8128 0.4572)
			(end -0.8128 0.4572)
			(stroke
				(width 0.1)
				(type default)
			)
			(layer "F.Fab")
		)
		(fp_line
			(start 0.8128 -0.4572)
			(end 0.8128 0.4572)
			(stroke
				(width 0.1)
				(type default)
			)
			(layer "F.Fab")
		)
		(fp_line
			(start -0.8128 0.4572)
			(end -0.8128 -0.4572)
			(stroke
				(width 0.1)
				(type default)
			)
			(layer "F.Fab")
		)
		(fp_line
			(start -0.8128 -0.4572)
			(end 0.8128 -0.4572)
			(stroke
				(width 0.1)
				(type default)
			)
			(layer "F.Fab")
		)
		(pad "1" smd rect
			(at -0.6858 0 180)
			(size 0.762 0.8636)
			(layers "F.Cu" "F.Mask" "F.Paste")
			(net "XP1R8V_FPGA")
		)
		(pad "2" smd rect
			(at 0.6858 0 180)
			(size 0.762 0.8636)
			(layers "F.Cu" "F.Mask" "F.Paste")
			(net "XP1R8V_ICP10100")
		)
		(zone
			(layer "F.Cu")
			(hatch none 0.5)
			(connect_pads
				(clearance 0)
			)
			(min_thickness 0.25)
			(keepout
				(tracks not_allowed)
				(vias allowed)
				(pads allowed)
				(copperpour not_allowed)
				(footprints allowed)
			)
			(placement
				(enabled no)
				(sheetname "")
			)
			(fill
				(thermal_gap 0.5)
				(thermal_bridge_width 0.5)
				(island_removal_mode 0)
			)
			(polygon
				(pts
					(xy 23.659592 -67.31) (xy 23.354792 -67.31) (xy 23.354792 -66.3956) (xy 23.659592 -66.3956)
				)
			)
		)
		(zone
			(layer "F.Cu")
			(hatch none 0.5)
			(connect_pads
				(clearance 0)
			)
			(min_thickness 0.25)
			(keepout
				(tracks allowed)
				(vias not_allowed)
				(pads allowed)
				(copperpour not_allowed)
				(footprints allowed)
			)
			(placement
				(enabled no)
				(sheetname "")
			)
			(fill
				(thermal_gap 0.5)
				(thermal_bridge_width 0.5)
				(island_removal_mode 0)
			)
			(polygon
				(pts
					(xy 23.659592 -67.31) (xy 23.354792 -67.31) (xy 23.354792 -66.3956) (xy 23.659592 -66.3956)
				)
			)
		)
	)
	(footprint ""
		(layer "F.Cu")
		(at 56.134 -132.715)
		(property "Reference" "SP41"
			(at 0 0 0)
			(layer "F.SilkS")
			(hide yes)
			(effects
				(font
					(size 1.27 1.27)
				)
			)
		)
		(property "Value" ""
			(at 0 0 0)
			(layer "F.Fab")
			(effects
				(font
					(size 1.27 1.27)
				)
			)
		)
		(duplicate_pad_numbers_are_jumpers no)
	)
	(footprint ""
		(layer "F.Cu")
		(at 101.092 -87.4522 -90)
		(property "Reference" "U39"
			(at -2.7178 1.99263 90)
			(unlocked yes)
			(layer "F.SilkS")
			(effects
				(font
					(size 0.7874 0.5842)
					(thickness 0.1524)
				)
			)
		)
		(property "Value" ""
			(at 0 0 270)
			(layer "F.Fab")
			(effects
				(font
					(size 1.27 1.27)
				)
			)
		)
		(property "Device Type" "NLASB3157DFT2G_SC88-G223-10187A"
			(at 0.1524 2.168906 270)
			(unlocked yes)
			(layer "F.Fab")
			(hide yes)
			(effects
				(font
					(size 0.7874 0.5842)
					(thickness 0.000001)
				)
			)
		)
		(property "User Part Number" "PARTNUM*"
			(at 0.127 3.184906 270)
			(unlocked yes)
			(layer "Cmts.User")
			(hide yes)
			(effects
				(font
					(size 0.7874 0.5842)
					(thickness 0.000001)
				)
			)
		)
		(duplicate_pad_numbers_are_jumpers no)
		(fp_line
			(start -1.50876 1.354074)
			(end -1.50876 -1.354074)
			(stroke
				(width 0.1)
				(type default)
			)
			(layer "F.SilkS")
		)
		(fp_line
			(start 1.50876 1.354074)
			(end -1.50876 1.354074)
			(stroke
				(width 0.1)
				(type default)
			)
			(layer "F.SilkS")
		)
		(fp_line
			(start -1.50876 -1.354074)
			(end 1.50876 -1.354074)
			(stroke
				(width 0.1)
				(type default)
			)
			(layer "F.SilkS")
		)
		(fp_line
			(start 1.50876 -1.354074)
			(end 1.50876 1.354074)
			(stroke
				(width 0.1)
				(type default)
			)
			(layer "F.SilkS")
		)
		(fp_poly
			(pts
				(arc
					(start -2.159 -1.3716)
					(mid -2.159 -0.6096)
					(end -2.159 -1.3716)
				)
			)
			(stroke
				(width 0)
				(type default)
			)
			(fill yes)
			(layer "F.SilkS")
		)
		(fp_poly
			(pts
				(xy -1.76276 1.608074) (xy 1.76276 1.608074) (xy 1.76276 -1.608074) (xy -1.76276 -1.608074)
			)
			(stroke
				(width 0)
				(type default)
			)
			(fill no)
			(layer "F.CrtYd")
		)
		(fp_line
			(start -0.674878 1.100074)
			(end -0.674878 -1.100074)
			(stroke
				(width 0.1)
				(type default)
			)
			(layer "F.Fab")
		)
		(fp_line
			(start 0.674878 1.100074)
			(end -0.674878 1.100074)
			(stroke
				(width 0.1)
				(type default)
			)
			(layer "F.Fab")
		)
		(fp_line
			(start -0.674878 -1.100074)
			(end 0.674878 -1.100074)
			(stroke
				(width 0.1)
				(type default)
			)
			(layer "F.Fab")
		)
		(fp_line
			(start 0.674878 -1.100074)
			(end 0.674878 1.100074)
			(stroke
				(width 0.1)
				(type default)
			)
			(layer "F.Fab")
		)
		(fp_poly
			(pts
				(arc
					(start -2.159 -1.3716)
					(mid -2.159 -0.6096)
					(end -2.159 -1.3716)
				)
			)
			(stroke
				(width 0)
				(type default)
			)
			(fill yes)
			(layer "F.Fab")
		)
		(fp_text user "3"
			(at -0.83185 1.778 0)
			(unlocked yes)
			(layer "F.SilkS")
			(effects
				(font
					(size 0.635 0.4064)
					(thickness 0.1524)
				)
			)
		)
		(fp_text user "4"
			(at 2.08915 1.651 0)
			(unlocked yes)
			(layer "F.SilkS")
			(effects
				(font
					(size 0.635 0.4064)
					(thickness 0.1524)
				)
			)
		)
		(fp_text user "6"
			(at 2.08915 -1.651 0)
			(unlocked yes)
			(layer "F.SilkS")
			(effects
				(font
					(size 0.635 0.4064)
					(thickness 0.1524)
				)
			)
		)
		(fp_text user "4"
			(at 2.035048 0.924306 90)
			(unlocked yes)
			(layer "F.Fab")
			(effects
				(font
					(size 0.7874 0.5842)
					(thickness 0.1524)
				)
			)
		)
		(fp_text user "3"
			(at -1.995678 0.91313 90)
			(unlocked yes)
			(layer "F.Fab")
			(effects
				(font
					(size 0.7874 0.5842)
					(thickness 0.1524)
				)
			)
		)
		(fp_text user "6"
			(at 1.97104 -0.731774 90)
			(unlocked yes)
			(layer "F.Fab")
			(effects
				(font
					(size 0.7874 0.5842)
					(thickness 0.1524)
				)
			)
		)
		(pad "1" smd rect
			(at -0.94996 -0.649986 270)
			(size 0.6096 0.4318)
			(layers "F.Cu" "F.Mask" "F.Paste")
			(net "Net_787")
		)
		(pad "2" smd rect
			(at -0.94996 0 270)
			(size 0.6096 0.4318)
			(layers "F.Cu" "F.Mask" "F.Paste")
			(net "SG")
		)
		(pad "3" smd rect
			(at -0.94996 0.649986 270)
			(size 0.6096 0.4318)
			(layers "F.Cu" "F.Mask" "F.Paste")
			(net "FLASH_DQ2")
		)
		(pad "4" smd rect
			(at 0.94996 0.649986 270)
			(size 0.6096 0.4318)
			(layers "F.Cu" "F.Mask" "F.Paste")
			(net "FPGA_FLASH_DQ2")
		)
		(pad "5" smd rect
			(at 0.94996 0 270)
			(size 0.6096 0.4318)
			(layers "F.Cu" "F.Mask" "F.Paste")
			(net "XP3R3V_FPGA")
		)
		(pad "6" smd rect
			(at 0.94996 -0.649986 270)
			(size 0.6096 0.4318)
			(layers "F.Cu" "F.Mask" "F.Paste")
			(net "MUX2_SEL")
		)
	)
	(footprint ""
		(layer "F.Cu")
		(at 107.442 -59.7916)
		(property "Reference" "TP185"
			(at 2.82575 0.7874 90)
			(unlocked yes)
			(layer "F.SilkS")
			(effects
				(font
					(size 0.635 0.4064)
					(thickness 0.1524)
				)
				(justify left)
			)
		)
		(property "Value" ""
			(at 0 0 0)
			(layer "F.Fab")
			(effects
				(font
					(size 1.27 1.27)
				)
			)
		)
		(property "Device Type" "TP_PIONT-TP010CT020B030_PTH-TPA"
			(at -1.341882 0.996696 0)
			(unlocked yes)
			(layer "F.Fab")
			(hide yes)
			(effects
				(font
					(size 0.7874 0.5842)
					(thickness 0.1524)
				)
				(justify left)
			)
		)
		(duplicate_pad_numbers_are_jumpers no)
		(fp_poly
			(pts
				(arc
					(start 0.889 0)
					(mid -0.889 0)
					(end 0.889 0)
				)
			)
			(stroke
				(width 0)
				(type default)
			)
			(fill no)
			(layer "B.CrtYd")
		)
		(fp_poly
			(pts
				(arc
					(start 0.889 0)
					(mid -0.889 0)
					(end 0.889 0)
				)
			)
			(stroke
				(width 0)
				(type default)
			)
			(fill no)
			(layer "F.CrtYd")
		)
		(pad "1" thru_hole circle
			(at 0 0)
			(size 0.508 0.508)
			(drill 0.254)
			(layers "*.Cu" "*.Mask")
			(remove_unused_layers no)
			(net "IO_L23P_16")
			(clearance 0.1016)
			(padstack
				(mode front_inner_back)
				(layer "Inner"
					(shape circle)
					(size 0.508 0.508)
					(clearance 0.1016)
				)
				(layer "B.Cu"
					(shape circle)
					(size 0.762 0.762)
					(clearance -0.0254)
				)
			)
		)
	)
	(footprint ""
		(layer "F.Cu")
		(at 75.5904 -15.7734)
		(property "Reference" "R63"
			(at 0.3556 -2.98323 0)
			(unlocked yes)
			(layer "F.SilkS")
			(effects
				(font
					(size 0.7874 0.5842)
					(thickness 0.1524)
				)
			)
		)
		(property "Value" "VAL*"
			(at 0.02032 2.13233 0)
			(unlocked yes)
			(layer "F.Fab")
			(hide yes)
			(effects
				(font
					(size 0.7874 0.5842)
					(thickness 0.1524)
				)
			)
		)
		(property "Tolerance" "TOL*"
			(at 0.044704 3.05435 0)
			(unlocked yes)
			(layer "Cmts.User")
			(hide yes)
			(effects
				(font
					(size 0.7874 0.5842)
					(thickness 0.1524)
				)
			)
		)
		(property "User Part Number" "PARTNUM*"
			(at 0.02032 4.024884 0)
			(unlocked yes)
			(layer "Cmts.User")
			(hide yes)
			(effects
				(font
					(size 0.7874 0.5842)
					(thickness 0.1524)
				)
			)
		)
		(property "Device Type" "RESISTOR-G155-14701-01,4.7KOHMA"
			(at 0.008382 1.210564 0)
			(unlocked yes)
			(layer "F.Fab")
			(hide yes)
			(effects
				(font
					(size 0.7874 0.5842)
					(thickness 0.1524)
				)
			)
		)
		(duplicate_pad_numbers_are_jumpers no)
		(fp_line
			(start -1.143 -0.5588)
			(end -1.143 0.5588)
			(stroke
				(width 0.1)
				(type default)
			)
			(layer "F.SilkS")
		)
		(fp_line
			(start -1.143 0.5588)
			(end 1.143 0.5588)
			(stroke
				(width 0.1)
				(type default)
			)
			(layer "F.SilkS")
		)
		(fp_line
			(start 1.143 -0.5588)
			(end -1.143 -0.5588)
			(stroke
				(width 0.1)
				(type default)
			)
			(layer "F.SilkS")
		)
		(fp_line
			(start 1.143 0.5588)
			(end 1.143 -0.5588)
			(stroke
				(width 0.1)
				(type default)
			)
			(layer "F.SilkS")
		)
		(fp_poly
			(pts
				(xy -1.143 0.5588) (xy 1.143 0.5588) (xy 1.143 -0.5588) (xy -1.143 -0.5588)
			)
			(stroke
				(width 0)
				(type default)
			)
			(fill no)
			(layer "F.CrtYd")
		)
		(fp_line
			(start -0.508 -0.3048)
			(end -0.508 0.3048)
			(stroke
				(width 0.1)
				(type default)
			)
			(layer "F.Fab")
		)
		(fp_line
			(start -0.508 0.3048)
			(end 0.508 0.3048)
			(stroke
				(width 0.1)
				(type default)
			)
			(layer "F.Fab")
		)
		(fp_line
			(start 0.508 -0.3048)
			(end -0.508 -0.3048)
			(stroke
				(width 0.1)
				(type default)
			)
			(layer "F.Fab")
		)
		(fp_line
			(start 0.508 0.3048)
			(end 0.508 -0.3048)
			(stroke
				(width 0.1)
				(type default)
			)
			(layer "F.Fab")
		)
		(pad "1" smd rect
			(at -0.5334 0)
			(size 0.7112 0.6096)
			(layers "F.Cu" "F.Mask" "F.Paste")
			(net "XP3R3V_FPGA")
		)
		(pad "2" smd rect
			(at 0.5334 0)
			(size 0.7112 0.6096)
			(layers "F.Cu" "F.Mask" "F.Paste")
			(net "PCIE_PERST_N")
		)
		(zone
			(layer "F.Cu")
			(hatch none 0.5)
			(connect_pads
				(clearance 0)
			)
			(min_thickness 0.25)
			(keepout
				(tracks not_allowed)
				(vias allowed)
				(pads allowed)
				(copperpour not_allowed)
				(footprints allowed)
			)
			(placement
				(enabled no)
				(sheetname "")
			)
			(fill
				(thermal_gap 0.5)
				(thermal_bridge_width 0.5)
				(island_removal_mode 0)
			)
			(polygon
				(pts
					(xy 75.5142 -15.4686) (xy 75.6666 -15.4686) (xy 75.6666 -16.0782) (xy 75.5142 -16.0782)
				)
			)
		)
		(zone
			(layer "F.Cu")
			(hatch none 0.5)
			(connect_pads
				(clearance 0)
			)
			(min_thickness 0.25)
			(keepout
				(tracks allowed)
				(vias not_allowed)
				(pads allowed)
				(copperpour not_allowed)
				(footprints allowed)
			)
			(placement
				(enabled no)
				(sheetname "")
			)
			(fill
				(thermal_gap 0.5)
				(thermal_bridge_width 0.5)
				(island_removal_mode 0)
			)
			(polygon
				(pts
					(xy 75.5142 -15.4686) (xy 75.6666 -15.4686) (xy 75.6666 -16.0782) (xy 75.5142 -16.0782)
				)
			)
		)
	)
)
